# GMSL Serializer — KiCad project settings (.kicad_pro: net classes, design rules, text variables)
{
  "board": {
    "3dviewports": [],
    "design_settings": {
      "defaults": {
        "apply_defaults_to_fp_fields": false,
        "apply_defaults_to_fp_shapes": false,
        "apply_defaults_to_fp_text": false,
        "board_outline_line_width": 0.05,
        "copper_line_width": 0.2,
        "copper_text_italic": false,
        "copper_text_size_h": 1.5,
        "copper_text_size_v": 1.5,
        "copper_text_thickness": 0.3,
        "copper_text_upright": false,
        "courtyard_line_width": 0.05,
        "dimension_precision": 4,
        "dimension_units": 3,
        "dimensions": {
          "arrow_length": 1270000,
          "extension_offset": 500000,
          "keep_text_aligned": true,
          "suppress_zeroes": false,
          "text_position": 0,
          "units_format": 1
        },
        "fab_line_width": 0.1,
        "fab_text_italic": false,
        "fab_text_size_h": 1.0,
        "fab_text_size_v": 1.0,
        "fab_text_thickness": 0.15,
        "fab_text_upright": false,
        "other_line_width": 0.1,
        "other_text_italic": false,
        "other_text_size_h": 1.0,
        "other_text_size_v": 1.0,
        "other_text_thickness": 0.15,
        "other_text_upright": false,
        "pads": {
          "drill": 3.0,
          "height": 6.0,
          "width": 6.0
        },
        "silk_line_width": 0.12,
        "silk_text_italic": false,
        "silk_text_size_h": 1.0,
        "silk_text_size_v": 1.0,
        "silk_text_thickness": 0.15,
        "silk_text_upright": false,
        "zones": {
          "45_degree_only": false,
          "min_clearance": 0.2
        }
      },
      "diff_pair_dimensions": [
        {
          "gap": 0.0,
          "via_gap": 0.0,
          "width": 0.0
        },
        {
          "gap": 0.279,
          "via_gap": 0.321,
          "width": 0.186
        },
        {
          "gap": 0.196,
          "via_gap": 0.321,
          "width": 0.187
        }
      ],
      "drc_exclusions": [],
      "meta": {
        "version": 2
      },
      "rule_severities": {
        "annular_width": "error",
        "clearance": "error",
        "connection_width": "warning",
        "copper_edge_clearance": "error",
        "copper_sliver": "warning",
        "courtyards_overlap": "error",
        "diff_pair_gap_out_of_range": "error",
        "diff_pair_uncoupled_length_too_long": "error",
        "drill_out_of_range": "error",
        "duplicate_footprints": "warning",
        "extra_footprint": "warning",
        "footprint": "error",
        "footprint_symbol_mismatch": "warning",
        "footprint_type_mismatch": "error",
        "hole_clearance": "error",
        "hole_near_hole": "error",
        "holes_co_located": "warning",
        "invalid_outline": "error",
        "isolated_copper": "warning",
        "item_on_disabled_layer": "error",
        "items_not_allowed": "error",
        "length_out_of_range": "error",
        "lib_footprint_issues": "warning",
        "lib_footprint_mismatch": "warning",
        "malformed_courtyard": "error",
        "microvia_drill_out_of_range": "error",
        "missing_courtyard": "warning",
        "missing_footprint": "warning",
        "net_conflict": "warning",
        "npth_inside_courtyard": "warning",
        "padstack": "error",
        "pth_inside_courtyard": "warning",
        "shorting_items": "error",
        "silk_edge_clearance": "warning",
        "silk_over_copper": "warning",
        "silk_overlap": "warning",
        "skew_out_of_range": "error",
        "solder_mask_bridge": "error",
        "starved_thermal": "error",
        "text_height": "warning",
        "text_thickness": "warning",
        "through_hole_pad_without_hole": "error",
        "too_many_vias": "error",
        "track_dangling": "warning",
        "track_width": "error",
        "tracks_crossing": "error",
        "unconnected_items": "error",
        "unresolved_variable": "error",
        "via_dangling": "warning",
        "zones_intersect": "error"
      },
      "rules": {
        "allow_blind_buried_vias": false,
        "allow_microvias": false,
        "max_error": 0.005,
        "min_clearance": 0.125,
        "min_connection": 0.125,
        "min_copper_edge_clearance": 0.4,
        "min_hole_clearance": 0.25,
        "min_hole_to_hole": 0.25,
        "min_microvia_diameter": 0.2,
        "min_microvia_drill": 0.1,
        "min_resolved_spokes": 1,
        "min_silk_clearance": 0.0,
        "min_text_height": 0.7,
        "min_text_thickness": 0.08,
        "min_through_hole_diameter": 0.25,
        "min_track_width": 0.125,
        "min_via_annular_width": 0.05,
        "min_via_diameter": 0.6,
        "solder_mask_clearance": 0.0,
        "solder_mask_min_width": 0.0,
        "solder_mask_to_copper_clearance": 0.0,
        "use_height_for_length_calcs": true
      },
      "teardrop_options": [
        {
          "td_onpadsmd": true,
          "td_onroundshapesonly": false,
          "td_ontrackend": false,
          "td_onviapad": true
        }
      ],
      "teardrop_parameters": [
        {
          "td_allow_use_two_tracks": true,
          "td_curve_segcount": 0,
          "td_height_ratio": 1.0,
          "td_length_ratio": 0.5,
          "td_maxheight": 2.0,
          "td_maxlen": 1.0,
          "td_on_pad_in_zone": false,
          "td_target_name": "td_round_shape",
          "td_width_to_size_filter_ratio": 0.9
        },
        {
          "td_allow_use_two_tracks": true,
          "td_curve_segcount": 0,
          "td_height_ratio": 1.0,
          "td_length_ratio": 0.5,
          "td_maxheight": 2.0,
          "td_maxlen": 1.0,
          "td_on_pad_in_zone": false,
          "td_target_name": "td_rect_shape",
          "td_width_to_size_filter_ratio": 0.9
        },
        {
          "td_allow_use_two_tracks": true,
          "td_curve_segcount": 0,
          "td_height_ratio": 1.0,
          "td_length_ratio": 0.5,
          "td_maxheight": 2.0,
          "td_maxlen": 1.0,
          "td_on_pad_in_zone": false,
          "td_target_name": "td_track_end",
          "td_width_to_size_filter_ratio": 0.9
        }
      ],
      "track_widths": [
        0.0,
        0.187,
        0.2,
        0.3,
        0.5
      ],
      "tuning_pattern_settings": {
        "diff_pair_defaults": {
          "corner_radius_percentage": 80,
          "corner_style": 1,
          "max_amplitude": 1.0,
          "min_amplitude": 0.2,
          "single_sided": false,
          "spacing": 1.0
        },
        "diff_pair_skew_defaults": {
          "corner_radius_percentage": 80,
          "corner_style": 1,
          "max_amplitude": 1.0,
          "min_amplitude": 0.2,
          "single_sided": false,
          "spacing": 0.6
        },
        "single_track_defaults": {
          "corner_radius_percentage": 80,
          "corner_style": 1,
          "max_amplitude": 1.0,
          "min_amplitude": 0.2,
          "single_sided": false,
          "spacing": 0.6
        }
      },
      "via_dimensions": [
        {
          "diameter": 0.0,
          "drill": 0.0
        },
        {
          "diameter": 0.55,
          "drill": 0.25
        }
      ],
      "zones_allow_external_fillets": false,
      "zones_use_no_outline": true
    },
    "ipc2581": {
      "dist": "",
      "distpn": "",
      "internal_id": "",
      "mfg": "",
      "mpn": ""
    },
    "layer_presets": [],
    "viewports": []
  },
  "boards": [],
  "cvpcb": {
    "equivalence_files": []
  },
  "erc": {
    "erc_exclusions": [],
    "meta": {
      "version": 0
    },
    "pin_map": [
      [
        0,
        0,
        0,
        0,
        0,
        0,
        1,
        0,
        0,
        0,
        0,
        2
      ],
      [
        0,
        2,
        0,
        1,
        0,
        0,
        1,
        0,
        2,
        2,
        2,
        2
      ],
      [
        0,
        0,
        0,
        0,
        0,
        0,
        1,
        0,
        1,
        0,
        1,
        2
      ],
      [
        0,
        1,
        0,
        0,
        0,
        0,
        1,
        1,
        2,
        1,
        1,
        2
      ],
      [
        0,
        0,
        0,
        0,
        0,
        0,
        1,
        0,
        0,
        0,
        0,
        2
      ],
      [
        0,
        0,
        0,
        0,
        0,
        0,
        0,
        0,
        0,
        0,
        0,
        2
      ],
      [
        1,
        1,
        1,
        1,
        1,
        0,
        1,
        1,
        1,
        1,
        1,
        2
      ],
      [
        0,
        0,
        0,
        1,
        0,
        0,
        1,
        0,
        0,
        0,
        0,
        2
      ],
      [
        0,
        2,
        1,
        2,
        0,
        0,
        1,
        0,
        2,
        2,
        2,
        2
      ],
      [
        0,
        2,
        0,
        1,
        0,
        0,
        1,
        0,
        2,
        0,
        0,
        2
      ],
      [
        0,
        2,
        1,
        1,
        0,
        0,
        1,
        0,
        2,
        0,
        0,
        2
      ],
      [
        2,
        2,
        2,
        2,
        2,
        2,
        2,
        2,
        2,
        2,
        2,
        2
      ]
    ],
    "rule_severities": {
      "bus_definition_conflict": "error",
      "bus_entry_needed": "error",
      "bus_to_bus_conflict": "error",
      "bus_to_net_conflict": "error",
      "conflicting_netclasses": "error",
      "different_unit_footprint": "error",
      "different_unit_net": "error",
      "duplicate_reference": "error",
      "duplicate_sheet_names": "error",
      "endpoint_off_grid": "warning",
      "extra_units": "error",
      "global_label_dangling": "warning",
      "hier_label_mismatch": "error",
      "label_dangling": "error",
      "lib_symbol_issues": "warning",
      "missing_bidi_pin": "warning",
      "missing_input_pin": "warning",
      "missing_power_pin": "error",
      "missing_unit": "warning",
      "multiple_net_names": "warning",
      "net_not_bus_member": "warning",
      "no_connect_connected": "error",
      "no_connect_dangling": "warning",
      "pin_not_connected": "error",
      "pin_not_driven": "error",
      "pin_to_pin": "ignore",
      "power_pin_not_driven": "error",
      "similar_labels": "warning",
      "simulation_model_issue": "ignore",
      "unannotated": "error",
      "unit_value_mismatch": "error",
      "unresolved_variable": "error",
      "wire_dangling": "error"
    }
  },
  "libraries": {
    "pinned_footprint_libs": [],
    "pinned_symbol_libs": []
  },
  "meta": {
    "filename": "gmsl-serializer.kicad_pro",
    "version": 1
  },
  "net_settings": {
    "classes": [
      {
        "bus_width": 12,
        "clearance": 0.125,
        "diff_pair_gap": 0.125,
        "diff_pair_via_gap": 0.25,
        "diff_pair_width": 0.125,
        "line_style": 0,
        "microvia_diameter": 0.3,
        "microvia_drill": 0.1,
        "name": "Default",
        "pcb_color": "rgba(0, 0, 0, 0.000)",
        "schematic_color": "rgba(0, 0, 0, 0.000)",
        "track_width": 0.2,
        "via_diameter": 0.6,
        "via_drill": 0.35,
        "wire_width": 6
      },
      {
        "bus_width": 12,
        "clearance": 0.125,
        "diff_pair_gap": 0.125,
        "diff_pair_via_gap": 0.25,
        "diff_pair_width": 0.125,
        "line_style": 0,
        "microvia_diameter": 0.3,
        "microvia_drill": 0.1,
        "name": "50Ohm-se_GMSL",
        "pcb_color": "rgba(0, 0, 0, 0.000)",
        "schematic_color": "rgba(0, 0, 0, 0.000)",
        "track_width": 0.187,
        "via_diameter": 0.6,
        "via_drill": 0.35,
        "wire_width": 6
      },
      {
        "bus_width": 12,
        "clearance": 0.125,
        "diff_pair_gap": 0.185,
        "diff_pair_via_gap": 0.25,
        "diff_pair_width": 0.18,
        "line_style": 0,
        "microvia_diameter": 0.3,
        "microvia_drill": 0.1,
        "name": "90Ohm-diff_CSI",
        "pcb_color": "rgba(0, 0, 0, 0.000)",
        "schematic_color": "rgba(0, 0, 0, 0.000)",
        "track_width": 0.18,
        "via_diameter": 0.6,
        "via_drill": 0.35,
        "wire_width": 6
      }
    ],
    "meta": {
      "version": 3
    },
    "net_colors": null,
    "netclass_assignments": null,
    "netclass_patterns": [
      {
        "netclass": "90Ohm-diff_CSI",
        "pattern": "**CSI.*"
      },
      {
        "netclass": "50Ohm-se_GMSL",
        "pattern": "**SIO*"
      }
    ]
  },
  "pcbnew": {
    "last_paths": {
      "gencad": "",
      "idf": "",
      "netlist": "",
      "plot": "",
      "pos_files": "",
      "specctra_dsn": "",
      "step": "",
      "svg": "",
      "vrml": ""
    },
    "page_layout_descr_file": ""
  },
  "schematic": {
    "annotate_start_num": 0,
    "bom_export_filename": "",
    "bom_fmt_presets": [],
    "bom_fmt_settings": {
      "field_delimiter": ",",
      "keep_line_breaks": false,
      "keep_tabs": false,
      "name": "CSV",
      "ref_delimiter": ",",
      "ref_range_delimiter": "",
      "string_delimiter": "\""
    },
    "bom_presets": [],
    "bom_settings": {
      "exclude_dnp": false,
      "fields_ordered": [
        {
          "group_by": false,
          "label": "Reference",
          "name": "Reference",
          "show": true
        },
        {
          "group_by": true,
          "label": "Value",
          "name": "Value",
          "show": true
        },
        {
          "group_by": false,
          "label": "Datasheet",
          "name": "Datasheet",
          "show": true
        },
        {
          "group_by": false,
          "label": "Footprint",
          "name": "Footprint",
          "show": true
        },
        {
          "group_by": false,
          "label": "Qty",
          "name": "${QUANTITY}",
          "show": true
        },
        {
          "group_by": true,
          "label": "DNP",
          "name": "${DNP}",
          "show": true
        }
      ],
      "filter_string": "",
      "group_symbols": true,
      "name": "Grouped By Value",
      "sort_asc": true,
      "sort_field": "Reference"
    },
    "connection_grid_size": 50.0,
    "drawing": {
      "dashed_lines_dash_length_ratio": 12.0,
      "dashed_lines_gap_length_ratio": 3.0,
      "default_line_thickness": 6.0,
      "default_text_size": 50.0,
      "field_names": [],
      "intersheets_ref_own_page": false,
      "intersheets_ref_prefix": "",
      "intersheets_ref_short": false,
      "intersheets_ref_show": false,
      "intersheets_ref_suffix": "",
      "junction_size_choice": 3,
      "label_size_ratio": 0.375,
      "operating_point_overlay_i_precision": 3,
      "operating_point_overlay_i_range": "~A",
      "operating_point_overlay_v_precision": 3,
      "operating_point_overlay_v_range": "~V",
      "overbar_offset_ratio": 1.23,
      "pin_symbol_size": 25.0,
      "text_offset_ratio": 0.15
    },
    "legacy_lib_dir": "",
    "legacy_lib_list": [],
    "meta": {
      "version": 1
    },
    "net_format_name": "",
    "ngspice": {
      "fix_include_paths": true,
      "fix_passive_vals": false,
      "meta": {
        "version": 0
      },
      "model_mode": 0,
      "workbook_filename": ""
    },
    "page_layout_descr_file": "",
    "plot_directory": "",
    "spice_adjust_passive_values": false,
    "spice_current_sheet_as_root": false,
    "spice_external_command": "spice \"%I\"",
    "spice_model_current_sheet_as_root": true,
    "spice_save_all_currents": false,
    "spice_save_all_dissipations": false,
    "spice_save_all_voltages": false,
    "subpart_first_id": 65,
    "subpart_id_separator": 0
  },
  "sheets": [
    [
      "",
      "Root"
    ],
    [
      "",
      "CSI Connector"
    ],
    [
      "",
      "Supply"
    ],
    [
      "",
      "Serializer"
    ],
    [
      "",
      "GMSL Connector"
    ]
  ],
  "text_variables": {}
}
